(kicad_pcb
	(version 20260206)
	(generator "pcbnew")
	(generator_version "10.0")
	(general
		(thickness 1.6)
		(legacy_teardrops no)
	)
	(paper "A4")
	(title_block
		(title "Bryce Canyon_R.DPB_16317-1_OCP.brd")
		(comment 1 "Bryce Canyon / footprints 201-206 of 2099")
	)
	(layers
		(0 "F.Cu" signal "TOP")
		(4 "In1.Cu" signal "L2GND")
		(6 "In2.Cu" signal "L3")
		(8 "In3.Cu" signal "L4VCC")
		(10 "In4.Cu" signal "L5VCC")
		(12 "In5.Cu" signal "L6")
		(14 "In6.Cu" signal "L7GND")
		(2 "B.Cu" signal "BOTTOM")
		(9 "F.Adhes" user "F.Adhesive")
		(11 "B.Adhes" user "B.Adhesive")
		(13 "F.Paste" user "Package Geometry/Pastemask Top")
		(15 "B.Paste" user "Package Geometry/Pastemask Bottom")
		(5 "F.SilkS" user "Ref Des/Silkscreen Top")
		(7 "B.SilkS" user "Ref Des/Silkscreen Bottom")
		(1 "F.Mask" user "Board Geometry/Soldermask Top")
		(3 "B.Mask" user "Board Geometry/Soldermask Bottom")
		(17 "Dwgs.User" user "User.Drawings")
		(19 "Cmts.User" user "User.Comments")
		(21 "Eco1.User" user "User.Eco1")
		(23 "Eco2.User" user "User.Eco2")
		(25 "Edge.Cuts" user "Board Geometry/Outline")
		(27 "Margin" user)
		(31 "F.CrtYd" user "Package Geometry/Place Bound Top")
		(29 "B.CrtYd" user "Package Geometry/Place Bound Bottom")
		(35 "F.Fab" user "Ref Des/Assembly Top")
		(33 "B.Fab" user "Ref Des/Assembly Bottom")
	)
	(footprint ""
		(layer "F.Cu")
		(at 426.085 -262.001 -90)
		(property "Reference" "R302"
			(at 0 0 270)
			(layer "F.SilkS")
			(hide yes)
			(effects
				(font
					(size 1.27 1.27)
				)
			)
		)
		(property "Value" "2R6F-GP"
			(at -0.0508 -4.8514 270)
			(unlocked yes)
			(layer "F.Fab")
			(hide yes)
			(effects
				(font
					(size 1.016 1.016)
					(thickness 0.1524)
				)
			)
		)
		(property "Device Type" "R1206H26"
			(at 0 -6.3754 270)
			(unlocked yes)
			(layer "F.Fab")
			(hide yes)
			(effects
				(font
					(size 1.016 1.016)
					(thickness 0.1524)
				)
			)
		)
		(duplicate_pad_numbers_are_jumpers no)
		(fp_line
			(start -1.016 2.2352)
			(end -1.016 -2.2352)
			(stroke
				(width 0.1524)
				(type default)
			)
			(layer "F.SilkS")
		)
		(fp_line
			(start 1.016 2.2352)
			(end -1.016 2.2352)
			(stroke
				(width 0.1524)
				(type default)
			)
			(layer "F.SilkS")
		)
		(fp_line
			(start -1.016 -2.2352)
			(end 1.016 -2.2352)
			(stroke
				(width 0.1524)
				(type default)
			)
			(layer "F.SilkS")
		)
		(fp_line
			(start 1.016 -2.2352)
			(end 1.016 2.2352)
			(stroke
				(width 0.1524)
				(type default)
			)
			(layer "F.SilkS")
		)
		(fp_rect
			(start -1.0922 2.3114)
			(end 1.0922 -2.3114)
			(stroke
				(width 0)
				(type default)
			)
			(fill no)
			(layer "F.CrtYd")
		)
		(fp_poly
			(pts
				(xy -1.0922 -2.3114) (xy 1.0922 -2.3114) (xy 1.0922 2.3114) (xy -1.0922 2.3114)
			)
			(stroke
				(width 0)
				(type default)
			)
			(fill no)
			(layer "F.Fab")
		)
		(pad "1" smd rect
			(at 0 -1.397 270)
			(size 1.651 1.27)
			(layers "F.Cu" "F.Mask" "F.Paste")
			(net "P5V_HDD9")
		)
		(pad "2" smd rect
			(at 0 1.397 270)
			(size 1.651 1.27)
			(layers "F.Cu" "F.Mask" "F.Paste")
			(net "5V_PRE_9")
		)
	)
	(footprint ""
		(layer "F.Cu")
		(at 242.193064 -368.115088 -90)
		(property "Reference" "Q200"
			(at 0 0 270)
			(layer "F.SilkS")
			(hide yes)
			(effects
				(font
					(size 1.27 1.27)
				)
			)
		)
		(property "Value" "MMBT3904-3-GP"
			(at 0.10287 -10.29843 270)
			(unlocked yes)
			(layer "F.Fab")
			(hide yes)
			(effects
				(font
					(size 1.016 1.016)
					(thickness 0.1524)
				)
			)
		)
		(property "Device Type" "SOT23CBE2D4H44"
			(at 0.10287 -12.20343 270)
			(unlocked yes)
			(layer "F.Fab")
			(hide yes)
			(effects
				(font
					(size 1.016 1.016)
					(thickness 0.1524)
				)
			)
		)
		(duplicate_pad_numbers_are_jumpers no)
		(fp_line
			(start -1.651 1.778)
			(end 1.651 1.778)
			(stroke
				(width 0.1524)
				(type default)
			)
			(layer "F.SilkS")
		)
		(fp_line
			(start 1.651 1.778)
			(end 1.651 -1.778)
			(stroke
				(width 0.1524)
				(type default)
			)
			(layer "F.SilkS")
		)
		(fp_line
			(start -1.651 -1.778)
			(end -1.651 1.778)
			(stroke
				(width 0.1524)
				(type default)
			)
			(layer "F.SilkS")
		)
		(fp_line
			(start 1.651 -1.778)
			(end -1.651 -1.778)
			(stroke
				(width 0.1524)
				(type default)
			)
			(layer "F.SilkS")
		)
		(fp_poly
			(pts
				(xy -1.778 1.8796) (xy -1.778 -1.8796) (xy 1.778 -1.8796) (xy 1.778 1.8796)
			)
			(stroke
				(width 0)
				(type default)
			)
			(fill no)
			(layer "F.CrtYd")
		)
		(fp_poly
			(pts
				(xy -1.778 1.8796) (xy -1.778 -1.8796) (xy 1.778 -1.8796) (xy 1.778 1.8796)
			)
			(stroke
				(width 0)
				(type default)
			)
			(fill no)
			(layer "F.Fab")
		)
		(pad "B" smd custom
			(at -0.98425 0.9525 270)
			(size 0.1905 0.1905)
			(layers "F.Cu" "F.Mask" "F.Paste")
			(net "MB3_TEMP_B")
			(options
				(clearance outline)
				(anchor circle)
			)
			(primitives
				(gr_poly
					(pts
						(arc
							(start -0.1778 0.5715)
							(mid -0.321484 0.511984)
							(end -0.381 0.3683)
						)
						(arc
							(start -0.381 -0.3683)
							(mid -0.321484 -0.511984)
							(end -0.1778 -0.5715)
						)
						(arc
							(start 0.1778 -0.5715)
							(mid 0.321484 -0.511984)
							(end 0.381 -0.3683)
						)
						(arc
							(start 0.381 0.3683)
							(mid 0.321484 0.511984)
							(end 0.1778 0.5715)
						)
					)
					(width 0)
					(fill yes)
				)
			)
		)
		(pad "C" smd custom
			(at 0 -0.9525 270)
			(size 0.1905 0.1905)
			(layers "F.Cu" "F.Mask" "F.Paste")
			(net "MB3_TEMP_B")
			(options
				(clearance outline)
				(anchor circle)
			)
			(primitives
				(gr_poly
					(pts
						(arc
							(start -0.1778 0.5715)
							(mid -0.321484 0.511984)
							(end -0.381 0.3683)
						)
						(arc
							(start -0.381 -0.3683)
							(mid -0.321484 -0.511984)
							(end -0.1778 -0.5715)
						)
						(arc
							(start 0.1778 -0.5715)
							(mid 0.321484 -0.511984)
							(end 0.381 -0.3683)
						)
						(arc
							(start 0.381 0.3683)
							(mid 0.321484 0.511984)
							(end 0.1778 0.5715)
						)
					)
					(width 0)
					(fill yes)
				)
			)
		)
		(pad "E" smd custom
			(at 0.98425 0.9525 270)
			(size 0.1905 0.1905)
			(layers "F.Cu" "F.Mask" "F.Paste")
			(net "MB3_TEMP_E")
			(options
				(clearance outline)
				(anchor circle)
			)
			(primitives
				(gr_poly
					(pts
						(arc
							(start -0.1778 0.5715)
							(mid -0.321484 0.511984)
							(end -0.381 0.3683)
						)
						(arc
							(start -0.381 -0.3683)
							(mid -0.321484 -0.511984)
							(end -0.1778 -0.5715)
						)
						(arc
							(start 0.1778 -0.5715)
							(mid 0.321484 -0.511984)
							(end 0.381 -0.3683)
						)
						(arc
							(start 0.381 0.3683)
							(mid 0.321484 0.511984)
							(end 0.1778 0.5715)
						)
					)
					(width 0)
					(fill yes)
				)
			)
		)
	)
	(footprint ""
		(layer "F.Cu")
		(at 407.1366 -32.766 -90)
		(property "Reference" "R820"
			(at 0 0 270)
			(layer "F.SilkS")
			(hide yes)
			(effects
				(font
					(size 1.27 1.27)
				)
			)
		)
		(property "Value" "300KR2F-GP"
			(at 0.064008 -3.993896 270)
			(unlocked yes)
			(layer "F.Fab")
			(hide yes)
			(effects
				(font
					(size 1.016 1.016)
					(thickness 0.1524)
				)
			)
		)
		(property "Device Type" "R402H16"
			(at 0.064008 -5.517896 270)
			(unlocked yes)
			(layer "F.Fab")
			(hide yes)
			(effects
				(font
					(size 1.016 1.016)
					(thickness 0.1524)
				)
			)
		)
		(duplicate_pad_numbers_are_jumpers no)
		(fp_line
			(start -0.508 -0.9398)
			(end -0.508 0.9398)
			(stroke
				(width 0.1524)
				(type default)
			)
			(layer "F.SilkS")
		)
		(fp_line
			(start 0.508 -0.9398)
			(end -0.508 -0.9398)
			(stroke
				(width 0.1524)
				(type default)
			)
			(layer "F.SilkS")
		)
		(fp_rect
			(start -0.508 0.9398)
			(end 0.508 -0.9398)
			(stroke
				(width 0)
				(type default)
			)
			(fill no)
			(layer "F.CrtYd")
		)
		(fp_rect
			(start -0.508 0.9398)
			(end 0.508 -0.9398)
			(stroke
				(width 0)
				(type default)
			)
			(fill no)
			(layer "F.Fab")
		)
		(pad "1" smd custom
			(at 0 -0.4445 270)
			(size 0.1397 0.1397)
			(layers "F.Cu" "F.Mask" "F.Paste")
			(net "SW_HDD_N32")
			(options
				(clearance outline)
				(anchor circle)
			)
			(primitives
				(gr_poly
					(pts
						(arc
							(start -0.1778 -0.2794)
							(mid -0.249642 -0.249642)
							(end -0.2794 -0.1778)
						)
						(arc
							(start -0.2794 0.1778)
							(mid -0.249642 0.249642)
							(end -0.1778 0.2794)
						)
						(arc
							(start 0.1778 0.2794)
							(mid 0.249642 0.249642)
							(end 0.2794 0.1778)
						)
						(arc
							(start 0.2794 -0.1778)
							(mid 0.249642 -0.249642)
							(end 0.1778 -0.2794)
						)
					)
					(width 0)
					(fill yes)
				)
			)
		)
		(pad "2" smd custom
			(at 0 0.4445 270)
			(size 0.1397 0.1397)
			(layers "F.Cu" "F.Mask" "F.Paste")
			(net "P12V_B")
			(options
				(clearance outline)
				(anchor circle)
			)
			(primitives
				(gr_poly
					(pts
						(arc
							(start -0.1778 -0.2794)
							(mid -0.249642 -0.249642)
							(end -0.2794 -0.1778)
						)
						(arc
							(start -0.2794 0.1778)
							(mid -0.249642 0.249642)
							(end -0.1778 0.2794)
						)
						(arc
							(start 0.1778 0.2794)
							(mid 0.249642 0.249642)
							(end 0.2794 0.1778)
						)
						(arc
							(start 0.2794 -0.1778)
							(mid 0.249642 -0.249642)
							(end 0.1778 -0.2794)
						)
					)
					(width 0)
					(fill yes)
				)
			)
		)
	)
	(footprint ""
		(layer "F.Cu")
		(at 457.005944 -376.09526 180)
		(property "Reference" "Q218"
			(at 0 0 180)
			(layer "F.SilkS")
			(hide yes)
			(effects
				(font
					(size 1.27 1.27)
				)
			)
		)
		(property "Value" "2N7002KDW-GP"
			(at -2.3622 -8.2042 180)
			(unlocked yes)
			(layer "F.Fab")
			(hide yes)
			(effects
				(font
					(size 1.016 1.016)
					(thickness 0.1524)
				)
			)
		)
		(property "Device Type" "SOT-363H44"
			(at -2.3622 -10.1092 180)
			(unlocked yes)
			(layer "F.Fab")
			(hide yes)
			(effects
				(font
					(size 1.016 1.016)
					(thickness 0.1524)
				)
			)
		)
		(duplicate_pad_numbers_are_jumpers no)
		(fp_line
			(start 1.4478 1.7018)
			(end 1.4478 -1.7018)
			(stroke
				(width 0.1524)
				(type default)
			)
			(layer "F.SilkS")
		)
		(fp_line
			(start 1.4478 -1.7018)
			(end -1.4478 -1.7018)
			(stroke
				(width 0.1524)
				(type default)
			)
			(layer "F.SilkS")
		)
		(fp_line
			(start -1.27 1.524)
			(end -1.27 0.6604)
			(stroke
				(width 0.4826)
				(type default)
			)
			(layer "F.SilkS")
		)
		(fp_line
			(start -1.4478 1.7018)
			(end 1.4478 1.7018)
			(stroke
				(width 0.1524)
				(type default)
			)
			(layer "F.SilkS")
		)
		(fp_line
			(start -1.4478 -1.7018)
			(end -1.4478 1.7018)
			(stroke
				(width 0.1524)
				(type default)
			)
			(layer "F.SilkS")
		)
		(fp_poly
			(pts
				(xy -1.524 -1.778) (xy 1.524 -1.778) (xy 1.524 1.778) (xy -1.524 1.778)
			)
			(stroke
				(width 0)
				(type default)
			)
			(fill no)
			(layer "F.CrtYd")
		)
		(fp_poly
			(pts
				(xy -1.524 -1.778) (xy 1.524 -1.778) (xy 1.524 1.778) (xy -1.524 1.778)
			)
			(stroke
				(width 0)
				(type default)
			)
			(fill no)
			(layer "F.Fab")
		)
		(pad "1" smd rect
			(at -0.65024 0.9398 180)
			(size 0.4064 1.016)
			(layers "F.Cu" "F.Mask" "F.Paste")
			(net "GND")
		)
		(pad "2" smd rect
			(at 0 0.9398 180)
			(size 0.4064 1.016)
			(layers "F.Cu" "F.Mask" "F.Paste")
			(net "FAN_LED3_D")
		)
		(pad "3" smd rect
			(at 0.65024 0.9398 180)
			(size 0.4064 1.016)
			(layers "F.Cu" "F.Mask" "F.Paste")
			(net "FAN_LED3_D")
		)
		(pad "4" smd rect
			(at 0.65024 -0.9398 180)
			(size 0.4064 1.016)
			(layers "F.Cu" "F.Mask" "F.Paste")
			(net "GND")
		)
		(pad "5" smd rect
			(at 0 -0.9398 180)
			(size 0.4064 1.016)
			(layers "F.Cu" "F.Mask" "F.Paste")
			(net "FAN_LED3")
		)
		(pad "6" smd rect
			(at -0.65024 -0.9398 180)
			(size 0.4064 1.016)
			(layers "F.Cu" "F.Mask" "F.Paste")
			(net "FAN_LED3_D2")
		)
	)
	(footprint ""
		(layer "F.Cu")
		(at 417.966652 -17.4371)
		(property "Reference" "VIA68"
			(at 0 0 0)
			(layer "F.SilkS")
			(hide yes)
			(effects
				(font
					(size 1.27 1.27)
				)
			)
		)
		(property "Value" "100OHM-8L-2D36MM-L16-GP"
			(at -3.4036 -0.4572 0)
			(unlocked yes)
			(layer "F.Fab")
			(hide yes)
			(effects
				(font
					(size 1.016 1.016)
					(thickness 0.1524)
				)
			)
		)
		(property "Device Type" "VIA-PCIE-4P-427097"
			(at -3.4036 -1.9812 0)
			(unlocked yes)
			(layer "F.Fab")
			(hide yes)
			(effects
				(font
					(size 1.016 1.016)
					(thickness 0.1524)
				)
			)
		)
		(duplicate_pad_numbers_are_jumpers no)
		(fp_rect
			(start -2.1336 0.4826)
			(end 2.1336 -0.4826)
			(stroke
				(width 0)
				(type default)
			)
			(fill no)
			(layer "F.CrtYd")
		)
		(fp_rect
			(start -2.1336 0.4826)
			(end 2.1336 -0.4826)
			(stroke
				(width 0)
				(type default)
			)
			(fill no)
			(layer "F.Fab")
		)
		(pad "1" thru_hole circle
			(at -1.651 0)
			(size 0.508 0.508)
			(drill 0.254)
			(layers "*.Cu" "*.Mask")
			(remove_unused_layers no)
			(net "GND")
			(clearance 0.2286)
			(thermal_gap 0.2286)
		)
		(pad "2" thru_hole circle
			(at -0.635 0)
			(size 0.508 0.508)
			(drill 0.254)
			(layers "*.Cu" "*.Mask")
			(remove_unused_layers no)
			(net "PHY_DRV_B_TO_SCC_B_33_DP")
			(clearance 0.2286)
			(thermal_gap 0.2286)
		)
		(pad "3" thru_hole circle
			(at 0.635 0)
			(size 0.508 0.508)
			(drill 0.254)
			(layers "*.Cu" "*.Mask")
			(remove_unused_layers no)
			(net "PHY_DRV_B_TO_SCC_B_33_DN")
			(clearance 0.2286)
			(thermal_gap 0.2286)
		)
		(pad "4" thru_hole circle
			(at 1.651 0)
			(size 0.508 0.508)
			(drill 0.254)
			(layers "*.Cu" "*.Mask")
			(remove_unused_layers no)
			(net "GND")
			(clearance 0.2286)
			(thermal_gap 0.2286)
		)
	)
	(footprint ""
		(layer "F.Cu")
		(at 201.89952 -353.760786 90)
		(property "Reference" "Q199"
			(at 0 0 90)
			(layer "F.SilkS")
			(hide yes)
			(effects
				(font
					(size 1.27 1.27)
				)
			)
		)
		(property "Value" "IRFH8201TRPBF-GP"
			(at -4.2164 -4.3688 90)
			(unlocked yes)
			(layer "F.Fab")
			(hide yes)
			(effects
				(font
					(size 1.016 1.016)
					(thickness 0.1524)
				)
			)
		)
		(property "Device Type" "PPAK-5PH42"
			(at -4.2164 -5.8928 90)
			(unlocked yes)
			(layer "F.Fab")
			(hide yes)
			(effects
				(font
					(size 1.016 1.016)
					(thickness 0.1524)
				)
			)
		)
		(duplicate_pad_numbers_are_jumpers no)
		(fp_line
			(start 2.8956 -2.794)
			(end 2.8956 4.826)
			(stroke
				(width 0.1524)
				(type default)
			)
			(layer "F.SilkS")
		)
		(fp_line
			(start -2.8956 -2.794)
			(end 2.8956 -2.794)
			(stroke
				(width 0.1524)
				(type default)
			)
			(layer "F.SilkS")
		)
		(fp_line
			(start 2.8956 4.826)
			(end -2.8956 4.826)
			(stroke
				(width 0.1524)
				(type default)
			)
			(layer "F.SilkS")
		)
		(fp_line
			(start -2.8956 4.826)
			(end -2.8956 -2.794)
			(stroke
				(width 0.1524)
				(type default)
			)
			(layer "F.SilkS")
		)
		(fp_line
			(start -1.9431 4.9276)
			(end -3.0353 4.9276)
			(stroke
				(width 0.3302)
				(type default)
			)
			(layer "F.SilkS")
		)
		(fp_line
			(start -3.0353 4.9276)
			(end -3.0353 3.9624)
			(stroke
				(width 0.3302)
				(type default)
			)
			(layer "F.SilkS")
		)
		(fp_poly
			(pts
				(xy -2.3622 5.334) (xy -1.4986 5.334) (xy -1.9304 4.9022)
			)
			(stroke
				(width 0)
				(type default)
			)
			(fill yes)
			(layer "F.SilkS")
		)
		(fp_poly
			(pts
				(xy 0.3556 -0.3556) (xy 2.6416 -0.3556) (xy 2.6416 -2.54) (xy 0.3556 -2.54)
			)
			(stroke
				(width 0)
				(type default)
			)
			(fill yes)
			(layer "F.Paste")
		)
		(fp_poly
			(pts
				(xy -2.6416 -0.3556) (xy -0.3556 -0.3556) (xy -0.3556 -2.54) (xy -2.6416 -2.54)
			)
			(stroke
				(width 0)
				(type default)
			)
			(fill yes)
			(layer "F.Paste")
		)
		(fp_poly
			(pts
				(xy 0.3556 2.54) (xy 2.6416 2.54) (xy 2.6416 0.3556) (xy 0.3556 0.3556)
			)
			(stroke
				(width 0)
				(type default)
			)
			(fill yes)
			(layer "F.Paste")
		)
		(fp_poly
			(pts
				(xy -2.6416 2.54) (xy -0.3556 2.54) (xy -0.3556 0.3556) (xy -2.6416 0.3556)
			)
			(stroke
				(width 0)
				(type default)
			)
			(fill yes)
			(layer "F.Paste")
		)
		(fp_rect
			(start -2.5781 3.9878)
			(end 2.5781 -2.1082)
			(stroke
				(width 0)
				(type default)
			)
			(fill no)
			(layer "F.CrtYd")
		)
		(fp_poly
			(pts
				(xy -3.1496 5.08) (xy -3.1496 -3.048) (xy 3.1496 -3.048) (xy 3.1496 3.9751) (xy 2.5781 3.9751) (xy 2.5781 -2.1082)
				(xy -2.5781 -2.1082) (xy -2.5781 3.9878) (xy 3.1496 3.9878) (xy 3.1496 5.08)
			)
			(stroke
				(width 0)
				(type default)
			)
			(fill no)
			(layer "F.CrtYd")
		)
		(fp_rect
			(start -3.1496 5.08)
			(end 3.1496 -3.048)
			(stroke
				(width 0)
				(type default)
			)
			(fill no)
			(layer "F.Fab")
		)
		(pad "1" smd rect
			(at -1.905 3.81 90)
			(size 0.762 1.524)
			(layers "F.Cu" "F.Mask" "F.Paste")
			(net "P12V_IN")
		)
		(pad "2" smd rect
			(at -0.635 3.81 90)
			(size 0.762 1.524)
			(layers "F.Cu" "F.Mask" "F.Paste")
			(net "P12V_IN")
		)
		(pad "3" smd rect
			(at 0.635 3.81 90)
			(size 0.762 1.524)
			(layers "F.Cu" "F.Mask" "F.Paste")
			(net "P12V_IN")
		)
		(pad "4" smd rect
			(at 1.905 3.81 90)
			(size 0.762 1.524)
			(layers "F.Cu" "F.Mask" "F.Paste")
			(net "MB0_12V_CTRL_GATE6")
		)
		(pad "5" smd rect
			(at 0 0 90)
			(size 5.2832 5.08)
			(layers "F.Cu" "F.Mask" "F.Paste")
			(net "MB0_P12V_IN_R")
		)
		(pad "6" smd rect
			(at 0.635 -2.032 90)
			(size 0.0254 0.0254)
			(layers "F.Cu" "F.Mask" "F.Paste")
			(net "MB0_P12V_IN_R")
		)
		(pad "7" smd rect
			(at -0.635 -2.032 90)
			(size 0.0254 0.0254)
			(layers "F.Cu" "F.Mask" "F.Paste")
			(net "MB0_P12V_IN_R")
		)
		(pad "8" smd rect
			(at -1.905 -2.032 90)
			(size 0.0254 0.0254)
			(layers "F.Cu" "F.Mask" "F.Paste")
			(net "MB0_P12V_IN_R")
		)
	)
)
